# RDIMM DDR5 Tester — KiCad custom design rules (.kicad_dru)
(version 1)

(rule "50OHM_SE_outer" 
	(constraint track_width (opt 0.256mm))
	(constraint clearance (opt 0.1mm))
	(condition "(A.NetClass == '50Ohm-se')")
	(layer outer)
)

(rule "50OHM_SE_inner" 
	(constraint track_width (opt 0.1mm))
	(constraint clearance (opt 0.1mm))
	(condition "(A.NetClass == '50Ohm-se')")
	(layer inner)
)

(rule "PCIe_85Ohm_outer" 
# calculated as 85Ohm @ 50 Ohm SE
	(constraint track_width (opt 0.22mm) )
	(constraint diff_pair_gap (opt 0.16mm))
	(constraint clearance (opt 0.1mm))
	(condition "(A.NetClass == '85Ohm-diff_PCIe')")
	(layer outer)
)

(rule "PCIe_85Ohm_outer_FPGA" 
# calculated as 85Ohm @ 50 Ohm SE
	(constraint track_width (opt 0.1mm) )
	(constraint diff_pair_gap (opt 0.1mm))
	(constraint clearance (opt 0.1mm))
	(condition "A.NetClass == '85Ohm-diff_PCIe' && A.insideCourtyard('U34')")
	(layer outer)
)

(rule "DDR_80OHM_diff_outer" 
# calculated as 80Ohm @ 45 Ohm SE
	(constraint track_width (opt 0.26mm))
	(constraint diff_pair_gap (opt 0.2mm))
	(constraint clearance (opt 0.1mm))
	(condition "(A.NetClass == '80Ohm-diff_DQS') ")
	(layer outer)
)

(rule "DDR_40OHM_SE_outer" 
	(constraint track_width (opt 0.38mm))
	(constraint clearance (opt 0.1mm))
	(condition "(A.NetClass == '40Ohm-se_DQ')")
	(layer outer)
)

(rule "DDR_80OHM_diff_inner" 
# calculated as 80Ohm @ 45 Ohm SE
	(constraint track_width (opt 0.13mm))
	(constraint diff_pair_gap (opt 0.11mm))
	(constraint clearance (opt 0.1mm))
	(condition "(A.NetClass == '80Ohm-diff_DQS') ")
	(layer inner)
)

(rule "DDR_40OHM_SE_inner" 
	(constraint track_width (opt 0.148mm))
	(constraint clearance (opt 0.1mm))
	(condition "(A.NetClass == '40Ohm-se_DQ')")
	(layer inner)
)

(rule "100OHM_diff_inner" 
# calculated as 95Ohm @ 51 Ohm SE
	(constraint track_width (opt 0.1mm))
	(constraint diff_pair_gap (opt 0.15mm))
	(constraint clearance (opt 0.1mm))
	(condition "(A.NetClass == '100Ohm-diff') ")
	(layer inner)
)

(rule "100OHM_diff_outer" 
# calculated as 100Ohm @ 55 Ohm SE
	(constraint track_width (opt 0.16mm))
	(constraint diff_pair_gap (opt 0.15mm))
	(constraint clearance (opt 0.1mm))
	(condition "(A.NetClass == '100Ohm-diff') ")
	(layer outer)
)

(rule "90OHM_diff_outer" 
# calculated as 90Ohm @ 55 Ohm SE
	(constraint track_width (opt 0.2mm))
	(constraint diff_pair_gap (opt 0.13mm))
	(constraint clearance (opt 0.1mm))
	(condition "(A.NetClass == '90Ohm-diff') ")
	(layer outer)
)

(rule "DDR_80OHM_diff_inner" 
# calculated as 80Ohm @ 45 Ohm SE
	(constraint track_width (opt 0.1mm))
	(constraint diff_pair_gap (opt 0.1mm))
	(constraint clearance (opt 0.1mm))
	(condition "A.NetClass == '80Ohm-diff_DQS' && A.insideCourtyard('U34')")
	(layer inner)
)